# S9S_MB_2U (Grand Teton) — schematic netlist excerpt (pin names and nets, part order shuffled) for the footprints in the layout excerpt that follows; sources: Cadence DE-HDL packaged netlist, KiCad conversion of 03242023_DA0F0TMBIJ0_F0T_Motherboard_J_brd_V01_OCP.brd

R2476  Q_RES  200K 1% EMPTY  pkg 0402LF  page 194 : A = SMB_PCIE_M2_0_EN ; B = PWRGD_P1V8_PCH_AUX
C1879  Q_CAP  0.1UF 25V 10% X7R  pkg 0402  page 165 : A = P3V3_AUX ; B = GND
PC722_P0_3  Q_CAP  22UF 16V 20% X6S  pkg C0805  page 272 : A = SW_P12V_PVCCFA_EHV_FIVRA_CPU0_R ; B = GND

(kicad_pcb
	(version 20260206)
	(generator "pcbnew")
	(generator_version "10.0")
	(general
		(thickness 1.6)
		(legacy_teardrops no)
	)
	(paper "A4")
	(title_block
		(title "03242023_DA0F0TMBIJ0_F0T_Motherboard_J_brd_V01_OCP.brd")
		(comment 1 "Grand Teton / footprints 684-686 of 6105")
	)
	(layers
		(0 "F.Cu" signal "TOP")
		(4 "In1.Cu" signal "GND")
		(6 "In2.Cu" signal "IN1")
		(8 "In3.Cu" signal "GND1")
		(10 "In4.Cu" signal "IN2")
		(12 "In5.Cu" signal "GND2")
		(14 "In6.Cu" signal "IN3")
		(16 "In7.Cu" signal "GND3")
		(18 "In8.Cu" signal "VCC")
		(20 "In9.Cu" signal "VCC1")
		(22 "In10.Cu" signal "GND4")
		(24 "In11.Cu" signal "IN4")
		(26 "In12.Cu" signal "GND5")
		(28 "In13.Cu" signal "IN5")
		(30 "In14.Cu" signal "GND6")
		(32 "In15.Cu" signal "IN6")
		(34 "In16.Cu" signal "GND7")
		(2 "B.Cu" signal "BOTTOM")
		(9 "F.Adhes" user "F.Adhesive")
		(11 "B.Adhes" user "B.Adhesive")
		(13 "F.Paste" user "Package Geometry/Pastemask Top")
		(15 "B.Paste" user "Package Geometry/Pastemask Bottom")
		(5 "F.SilkS" user "Ref Des/Silkscreen Top")
		(7 "B.SilkS" user "Ref Des/Silkscreen Bottom")
		(1 "F.Mask" user "Board Geometry/Soldermask Top")
		(3 "B.Mask" user "Board Geometry/Soldermask Bottom")
		(17 "Dwgs.User" user "User.Drawings")
		(19 "Cmts.User" user "User.Comments")
		(21 "Eco1.User" user "User.Eco1")
		(23 "Eco2.User" user "User.Eco2")
		(25 "Edge.Cuts" user "Board Geometry/Outline")
		(27 "Margin" user)
		(31 "F.CrtYd" user "Package Geometry/Place Bound Top")
		(29 "B.CrtYd" user "Package Geometry/Place Bound Bottom")
		(35 "F.Fab" user "Ref Des/Assembly Top")
		(33 "B.Fab" user "Ref Des/Assembly Bottom")
	)
	(footprint ""
		(layer "F.Cu")
		(at 430.991518 -366.65027)
		(property "Reference" "PC722_P0_3"
			(at 0 0 0)
			(layer "F.SilkS")
			(hide yes)
			(effects
				(font
					(size 1.27 1.27)
				)
			)
		)
		(property "Value" ""
			(at 0 0 0)
			(layer "F.Fab")
			(effects
				(font
					(size 1.27 1.27)
				)
			)
		)
		(duplicate_pad_numbers_are_jumpers no)
		(fp_line
			(start -1.524 -0.762)
			(end 1.524 -0.762)
			(stroke
				(width 0.1524)
				(type default)
			)
			(layer "F.SilkS")
		)
		(fp_line
			(start -1.524 0.762)
			(end -1.524 -0.762)
			(stroke
				(width 0.1524)
				(type default)
			)
			(layer "F.SilkS")
		)
		(fp_line
			(start 1.524 -0.762)
			(end 1.524 0.762)
			(stroke
				(width 0.1524)
				(type default)
			)
			(layer "F.SilkS")
		)
		(fp_line
			(start 1.524 0.762)
			(end -1.524 0.762)
			(stroke
				(width 0.1524)
				(type default)
			)
			(layer "F.SilkS")
		)
		(fp_line
			(start -1.1049 -0.724916)
			(end -1.1049 0.724916)
			(stroke
				(width 0.1)
				(type default)
			)
			(layer "F.Fab")
		)
		(fp_line
			(start -1.1049 0.724916)
			(end 1.1049 0.724916)
			(stroke
				(width 0.1)
				(type default)
			)
			(layer "F.Fab")
		)
		(fp_line
			(start 1.1049 -0.724916)
			(end -1.1049 -0.724916)
			(stroke
				(width 0.1)
				(type default)
			)
			(layer "F.Fab")
		)
		(fp_line
			(start 1.1049 0.724916)
			(end 1.1049 -0.724916)
			(stroke
				(width 0.1)
				(type default)
			)
			(layer "F.Fab")
		)
		(pad "1" smd rect
			(at -0.889 0 180)
			(size 1.016 1.27)
			(layers "F.Cu" "F.Mask" "F.Paste")
			(net "SW_P12V_PVCCFA_EHV_FIVRA_CPU0_R")
		)
		(pad "2" smd rect
			(at 0.889 0 180)
			(size 1.016 1.27)
			(layers "F.Cu" "F.Mask" "F.Paste")
			(net "GND")
		)
	)
	(footprint ""
		(layer "F.Cu")
		(at 162.23488 -58.511948)
		(property "Reference" "R2476"
			(at 0 0 0)
			(layer "F.SilkS")
			(hide yes)
			(effects
				(font
					(size 1.27 1.27)
				)
			)
		)
		(property "Value" ""
			(at 0 0 0)
			(layer "F.Fab")
			(effects
				(font
					(size 1.27 1.27)
				)
			)
		)
		(duplicate_pad_numbers_are_jumpers no)
		(fp_line
			(start -0.7874 -0.4064)
			(end 0.7874 -0.4064)
			(stroke
				(width 0.1524)
				(type default)
			)
			(layer "F.SilkS")
		)
		(fp_line
			(start -0.7874 0.4064)
			(end -0.7874 -0.4064)
			(stroke
				(width 0.1524)
				(type default)
			)
			(layer "F.SilkS")
		)
		(fp_line
			(start 0.7874 -0.4064)
			(end 0.7874 0.4064)
			(stroke
				(width 0.1524)
				(type default)
			)
			(layer "F.SilkS")
		)
		(fp_line
			(start 0.7874 0.4064)
			(end -0.7874 0.4064)
			(stroke
				(width 0.1524)
				(type default)
			)
			(layer "F.SilkS")
		)
		(fp_line
			(start -0.67945 -0.305054)
			(end -0.12065 -0.305054)
			(stroke
				(width 0.1)
				(type default)
			)
			(layer "F.Fab")
		)
		(fp_line
			(start -0.67945 0.3048)
			(end -0.67945 -0.305054)
			(stroke
				(width 0.1)
				(type default)
			)
			(layer "F.Fab")
		)
		(fp_line
			(start -0.12065 -0.305054)
			(end -0.12065 -0.2794)
			(stroke
				(width 0.1)
				(type default)
			)
			(layer "F.Fab")
		)
		(fp_line
			(start -0.12065 -0.2794)
			(end 0.12065 -0.2794)
			(stroke
				(width 0.1)
				(type default)
			)
			(layer "F.Fab")
		)
		(fp_line
			(start -0.12065 0.2794)
			(end -0.12065 0.3048)
			(stroke
				(width 0.1)
				(type default)
			)
			(layer "F.Fab")
		)
		(fp_line
			(start -0.12065 0.3048)
			(end -0.67945 0.3048)
			(stroke
				(width 0.1)
				(type default)
			)
			(layer "F.Fab")
		)
		(fp_line
			(start 0.120396 0.2794)
			(end -0.12065 0.2794)
			(stroke
				(width 0.1)
				(type default)
			)
			(layer "F.Fab")
		)
		(fp_line
			(start 0.120396 0.3048)
			(end 0.120396 0.2794)
			(stroke
				(width 0.1)
				(type default)
			)
			(layer "F.Fab")
		)
		(fp_line
			(start 0.12065 -0.3048)
			(end 0.67945 -0.3048)
			(stroke
				(width 0.1)
				(type default)
			)
			(layer "F.Fab")
		)
		(fp_line
			(start 0.12065 -0.2794)
			(end 0.12065 -0.3048)
			(stroke
				(width 0.1)
				(type default)
			)
			(layer "F.Fab")
		)
		(fp_line
			(start 0.67945 -0.3048)
			(end 0.67945 0.3048)
			(stroke
				(width 0.1)
				(type default)
			)
			(layer "F.Fab")
		)
		(fp_line
			(start 0.67945 0.3048)
			(end 0.120396 0.3048)
			(stroke
				(width 0.1)
				(type default)
			)
			(layer "F.Fab")
		)
		(pad "1" smd circle
			(at -0.40005 0)
			(size 0 0)
			(layers "F.Cu" "F.Mask" "F.Paste")
			(net "SMB_PCIE_M2_0_EN")
		)
		(pad "2" smd circle
			(at 0.40005 0)
			(size 0 0)
			(layers "F.Cu" "F.Mask" "F.Paste")
			(net "PWRGD_P1V8_PCH_AUX")
		)
	)
	(footprint ""
		(layer "F.Cu")
		(at 140.70838 -33.466024)
		(property "Reference" "C1879"
			(at 0 0 0)
			(layer "F.SilkS")
			(hide yes)
			(effects
				(font
					(size 1.27 1.27)
				)
			)
		)
		(property "Value" ""
			(at 0 0 0)
			(layer "F.Fab")
			(effects
				(font
					(size 1.27 1.27)
				)
			)
		)
		(duplicate_pad_numbers_are_jumpers no)
		(fp_line
			(start -0.7874 -0.4064)
			(end 0.7874 -0.4064)
			(stroke
				(width 0.1524)
				(type default)
			)
			(layer "F.SilkS")
		)
		(fp_line
			(start -0.7874 0.4064)
			(end -0.7874 -0.4064)
			(stroke
				(width 0.1524)
				(type default)
			)
			(layer "F.SilkS")
		)
		(fp_line
			(start 0.7874 -0.4064)
			(end 0.7874 0.4064)
			(stroke
				(width 0.1524)
				(type default)
			)
			(layer "F.SilkS")
		)
		(fp_line
			(start 0.7874 0.4064)
			(end -0.7874 0.4064)
			(stroke
				(width 0.1524)
				(type default)
			)
			(layer "F.SilkS")
		)
		(fp_line
			(start -0.67945 -0.305054)
			(end -0.12065 -0.305054)
			(stroke
				(width 0.1)
				(type default)
			)
			(layer "F.Fab")
		)
		(fp_line
			(start -0.67945 0.3048)
			(end -0.67945 -0.305054)
			(stroke
				(width 0.1)
				(type default)
			)
			(layer "F.Fab")
		)
		(fp_line
			(start -0.12065 -0.305054)
			(end -0.12065 -0.2794)
			(stroke
				(width 0.1)
				(type default)
			)
			(layer "F.Fab")
		)
		(fp_line
			(start -0.12065 -0.2794)
			(end 0.12065 -0.2794)
			(stroke
				(width 0.1)
				(type default)
			)
			(layer "F.Fab")
		)
		(fp_line
			(start -0.12065 0.2794)
			(end -0.12065 0.3048)
			(stroke
				(width 0.1)
				(type default)
			)
			(layer "F.Fab")
		)
		(fp_line
			(start -0.12065 0.3048)
			(end -0.67945 0.3048)
			(stroke
				(width 0.1)
				(type default)
			)
			(layer "F.Fab")
		)
		(fp_line
			(start 0.120396 0.2794)
			(end -0.12065 0.2794)
			(stroke
				(width 0.1)
				(type default)
			)
			(layer "F.Fab")
		)
		(fp_line
			(start 0.120396 0.3048)
			(end 0.120396 0.2794)
			(stroke
				(width 0.1)
				(type default)
			)
			(layer "F.Fab")
		)
		(fp_line
			(start 0.12065 -0.3048)
			(end 0.67945 -0.3048)
			(stroke
				(width 0.1)
				(type default)
			)
			(layer "F.Fab")
		)
		(fp_line
			(start 0.12065 -0.2794)
			(end 0.12065 -0.3048)
			(stroke
				(width 0.1)
				(type default)
			)
			(layer "F.Fab")
		)
		(fp_line
			(start 0.67945 -0.3048)
			(end 0.67945 0.3048)
			(stroke
				(width 0.1)
				(type default)
			)
			(layer "F.Fab")
		)
		(fp_line
			(start 0.67945 0.3048)
			(end 0.120396 0.3048)
			(stroke
				(width 0.1)
				(type default)
			)
			(layer "F.Fab")
		)
		(pad "1" smd circle
			(at -0.40005 0)
			(size 0 0)
			(layers "F.Cu" "F.Mask" "F.Paste")
			(net "P3V3_AUX")
		)
		(pad "2" smd circle
			(at 0.40005 0)
			(size 0 0)
			(layers "F.Cu" "F.Mask" "F.Paste")
			(net "GND")
		)
	)
)
